(kicad_pcb
	(version 20260206)
	(generator "pcbnew")
	(generator_version "10.0")
	(general
		(thickness 1.6)
		(legacy_teardrops no)
	)
	(paper "A4")
	(title_block
		(title "peb — Lightning_PEB_BRD.brd")
		(comment 1 "Lightning (Wiwynn / Facebook NVMe JBOF) / footprints 1988-1996 of 2563")
	)
	(layers
		(0 "F.Cu" signal "TOP")
		(4 "In1.Cu" signal "L2GND")
		(6 "In2.Cu" signal "L3")
		(8 "In3.Cu" signal "L4VCC")
		(10 "In4.Cu" signal "L5VCC")
		(12 "In5.Cu" signal "L6")
		(14 "In6.Cu" signal "L7GND")
		(2 "B.Cu" signal "BOTTOM")
		(9 "F.Adhes" user "F.Adhesive")
		(11 "B.Adhes" user "B.Adhesive")
		(13 "F.Paste" user "Package Geometry/Pastemask Top")
		(15 "B.Paste" user "Package Geometry/Pastemask Bottom")
		(5 "F.SilkS" user "Ref Des/Silkscreen Top")
		(7 "B.SilkS" user "Ref Des/Silkscreen Bottom")
		(1 "F.Mask" user "Board Geometry/Soldermask Top")
		(3 "B.Mask" user "Board Geometry/Soldermask Bottom")
		(17 "Dwgs.User" user "User.Drawings")
		(19 "Cmts.User" user "User.Comments")
		(21 "Eco1.User" user "User.Eco1")
		(23 "Eco2.User" user "User.Eco2")
		(25 "Edge.Cuts" user "Board Geometry/Outline")
		(27 "Margin" user)
		(31 "F.CrtYd" user "Package Geometry/Place Bound Top")
		(29 "B.CrtYd" user "Package Geometry/Place Bound Bottom")
		(35 "F.Fab" user "Ref Des/Assembly Top")
		(33 "B.Fab" user "Ref Des/Assembly Bottom")
	)
	(footprint ""
		(layer "B.Cu")
		(at 58.166 -133.985 180)
		(property "Reference" "R434"
			(at 0 0 0)
			(layer "B.SilkS")
			(hide yes)
			(effects
				(font
					(size 1.27 1.27)
				)
				(justify mirror)
			)
		)
		(property "Value" "3K3R2F-2-GP"
			(at -0.064008 -3.993896 180)
			(unlocked yes)
			(layer "B.Fab")
			(hide yes)
			(effects
				(font
					(size 1.016 1.016)
					(thickness 0.1524)
				)
				(justify mirror)
			)
		)
		(property "Device Type" "R402H16"
			(at -0.064008 -5.517896 180)
			(unlocked yes)
			(layer "B.Fab")
			(hide yes)
			(effects
				(font
					(size 1.016 1.016)
					(thickness 0.1524)
				)
				(justify mirror)
			)
		)
		(duplicate_pad_numbers_are_jumpers no)
		(fp_line
			(start 0.508 -0.9398)
			(end 0.508 0.9398)
			(stroke
				(width 0.1524)
				(type default)
			)
			(layer "B.SilkS")
		)
		(fp_line
			(start -0.508 -0.9398)
			(end 0.508 -0.9398)
			(stroke
				(width 0.1524)
				(type default)
			)
			(layer "B.SilkS")
		)
		(fp_rect
			(start 0.508 0.9398)
			(end -0.508 -0.9398)
			(stroke
				(width 0)
				(type default)
			)
			(fill no)
			(layer "B.CrtYd")
		)
		(fp_rect
			(start 0.508 0.9398)
			(end -0.508 -0.9398)
			(stroke
				(width 0)
				(type default)
			)
			(fill no)
			(layer "B.Fab")
		)
		(pad "1" smd custom
			(at 0 -0.4445)
			(size 0.1397 0.1397)
			(layers "B.Cu" "B.Mask" "B.Paste")
			(net "ADC_P5V_STBY")
			(options
				(clearance outline)
				(anchor circle)
			)
			(primitives
				(gr_poly
					(pts
						(arc
							(start -0.1778 0.2794)
							(mid -0.249642 0.249642)
							(end -0.2794 0.1778)
						)
						(arc
							(start -0.2794 -0.1778)
							(mid -0.249642 -0.249642)
							(end -0.1778 -0.2794)
						)
						(arc
							(start 0.1778 -0.2794)
							(mid 0.249642 -0.249642)
							(end 0.2794 -0.1778)
						)
						(arc
							(start 0.2794 0.1778)
							(mid 0.249642 0.249642)
							(end 0.1778 0.2794)
						)
					)
					(width 0)
					(fill yes)
				)
			)
		)
		(pad "2" smd custom
			(at 0 0.4445)
			(size 0.1397 0.1397)
			(layers "B.Cu" "B.Mask" "B.Paste")
			(net "P5V_STBY")
			(options
				(clearance outline)
				(anchor circle)
			)
			(primitives
				(gr_poly
					(pts
						(arc
							(start -0.1778 0.2794)
							(mid -0.249642 0.249642)
							(end -0.2794 0.1778)
						)
						(arc
							(start -0.2794 -0.1778)
							(mid -0.249642 -0.249642)
							(end -0.1778 -0.2794)
						)
						(arc
							(start 0.1778 -0.2794)
							(mid 0.249642 -0.249642)
							(end 0.2794 -0.1778)
						)
						(arc
							(start 0.2794 0.1778)
							(mid 0.249642 0.249642)
							(end 0.1778 0.2794)
						)
					)
					(width 0)
					(fill yes)
				)
			)
		)
	)
	(footprint ""
		(layer "B.Cu")
		(at 238.9124 -59.0042 -90)
		(property "Reference" "C530"
			(at 0 0 90)
			(layer "B.SilkS")
			(hide yes)
			(effects
				(font
					(size 1.27 1.27)
				)
				(justify mirror)
			)
		)
		(property "Value" "SCD1U16V1KX-1-GP"
			(at 2.8321 -1.7399 270)
			(unlocked yes)
			(layer "B.Fab")
			(hide yes)
			(effects
				(font
					(size 1.016 1.016)
					(thickness 0.1524)
				)
				(justify mirror)
			)
		)
		(property "Device Type" "C0201H13"
			(at 2.8321 -3.2639 270)
			(unlocked yes)
			(layer "B.Fab")
			(hide yes)
			(effects
				(font
					(size 1.016 1.016)
					(thickness 0.1524)
				)
				(justify mirror)
			)
		)
		(duplicate_pad_numbers_are_jumpers no)
		(fp_rect
			(start 0.2794 0.6477)
			(end -0.2794 -0.6477)
			(stroke
				(width 0)
				(type default)
			)
			(fill no)
			(layer "B.CrtYd")
		)
		(fp_rect
			(start 0.2794 0.6477)
			(end -0.2794 -0.6477)
			(stroke
				(width 0)
				(type default)
			)
			(fill no)
			(layer "B.Fab")
		)
		(pad "1" smd custom
			(at 0 -0.2794 90)
			(size 0.0762 0.0762)
			(layers "B.Cu" "B.Mask" "B.Paste")
			(net "DUT_AVD_TX")
			(options
				(clearance outline)
				(anchor circle)
			)
			(primitives
				(gr_poly
					(pts
						(arc
							(start 0.1524 0.127)
							(mid 0.137521 0.162921)
							(end 0.1016 0.1778)
						)
						(arc
							(start -0.1016 0.1778)
							(mid -0.137521 0.162921)
							(end -0.1524 0.127)
						)
						(arc
							(start -0.1524 -0.127)
							(mid -0.137521 -0.162921)
							(end -0.1016 -0.1778)
						)
						(arc
							(start 0.1016 -0.1778)
							(mid 0.137521 -0.162921)
							(end 0.1524 -0.127)
						)
					)
					(width 0)
					(fill yes)
				)
			)
		)
		(pad "2" smd custom
			(at 0 0.2794 90)
			(size 0.0762 0.0762)
			(layers "B.Cu" "B.Mask" "B.Paste")
			(net "GND")
			(options
				(clearance outline)
				(anchor circle)
			)
			(primitives
				(gr_poly
					(pts
						(arc
							(start 0.1524 0.127)
							(mid 0.137521 0.162921)
							(end 0.1016 0.1778)
						)
						(arc
							(start -0.1016 0.1778)
							(mid -0.137521 0.162921)
							(end -0.1524 0.127)
						)
						(arc
							(start -0.1524 -0.127)
							(mid -0.137521 -0.162921)
							(end -0.1016 -0.1778)
						)
						(arc
							(start 0.1016 -0.1778)
							(mid 0.137521 -0.162921)
							(end 0.1524 -0.127)
						)
					)
					(width 0)
					(fill yes)
				)
			)
		)
	)
	(footprint ""
		(layer "B.Cu")
		(at 130.220466 -208.8769 180)
		(property "Reference" "R4128"
			(at 0 0 0)
			(layer "B.SilkS")
			(hide yes)
			(effects
				(font
					(size 1.27 1.27)
				)
				(justify mirror)
			)
		)
		(property "Value" "4K7R2F-GP"
			(at -0.064008 -3.993896 180)
			(unlocked yes)
			(layer "B.Fab")
			(hide yes)
			(effects
				(font
					(size 1.016 1.016)
					(thickness 0.1524)
				)
				(justify mirror)
			)
		)
		(property "Device Type" "R402H16"
			(at -0.064008 -5.517896 180)
			(unlocked yes)
			(layer "B.Fab")
			(hide yes)
			(effects
				(font
					(size 1.016 1.016)
					(thickness 0.1524)
				)
				(justify mirror)
			)
		)
		(duplicate_pad_numbers_are_jumpers no)
		(fp_line
			(start 0.508 -0.9398)
			(end 0.508 0.9398)
			(stroke
				(width 0.1524)
				(type default)
			)
			(layer "B.SilkS")
		)
		(fp_line
			(start -0.508 -0.9398)
			(end 0.508 -0.9398)
			(stroke
				(width 0.1524)
				(type default)
			)
			(layer "B.SilkS")
		)
		(fp_rect
			(start 0.508 0.9398)
			(end -0.508 -0.9398)
			(stroke
				(width 0)
				(type default)
			)
			(fill no)
			(layer "B.CrtYd")
		)
		(fp_rect
			(start 0.508 0.9398)
			(end -0.508 -0.9398)
			(stroke
				(width 0)
				(type default)
			)
			(fill no)
			(layer "B.Fab")
		)
		(pad "1" smd custom
			(at 0 -0.4445)
			(size 0.1397 0.1397)
			(layers "B.Cu" "B.Mask" "B.Paste")
			(net "SSD_PRSNT#7")
			(options
				(clearance outline)
				(anchor circle)
			)
			(primitives
				(gr_poly
					(pts
						(arc
							(start -0.1778 0.2794)
							(mid -0.249642 0.249642)
							(end -0.2794 0.1778)
						)
						(arc
							(start -0.2794 -0.1778)
							(mid -0.249642 -0.249642)
							(end -0.1778 -0.2794)
						)
						(arc
							(start 0.1778 -0.2794)
							(mid 0.249642 -0.249642)
							(end 0.2794 -0.1778)
						)
						(arc
							(start 0.2794 0.1778)
							(mid 0.249642 0.249642)
							(end 0.1778 0.2794)
						)
					)
					(width 0)
					(fill yes)
				)
			)
		)
		(pad "2" smd custom
			(at 0 0.4445)
			(size 0.1397 0.1397)
			(layers "B.Cu" "B.Mask" "B.Paste")
			(net "P3V3_STBY")
			(options
				(clearance outline)
				(anchor circle)
			)
			(primitives
				(gr_poly
					(pts
						(arc
							(start -0.1778 0.2794)
							(mid -0.249642 0.249642)
							(end -0.2794 0.1778)
						)
						(arc
							(start -0.2794 -0.1778)
							(mid -0.249642 -0.249642)
							(end -0.1778 -0.2794)
						)
						(arc
							(start 0.1778 -0.2794)
							(mid 0.249642 -0.249642)
							(end 0.2794 -0.1778)
						)
						(arc
							(start 0.2794 0.1778)
							(mid 0.249642 0.249642)
							(end 0.1778 0.2794)
						)
					)
					(width 0)
					(fill yes)
				)
			)
		)
	)
	(footprint ""
		(layer "B.Cu")
		(at 227.6856 -39.004748 -90)
		(property "Reference" "C571"
			(at 0 0 90)
			(layer "B.SilkS")
			(hide yes)
			(effects
				(font
					(size 1.27 1.27)
				)
				(justify mirror)
			)
		)
		(property "Value" "SCD1U16V1KX-1-GP"
			(at 2.8321 -1.7399 270)
			(unlocked yes)
			(layer "B.Fab")
			(hide yes)
			(effects
				(font
					(size 1.016 1.016)
					(thickness 0.1524)
				)
				(justify mirror)
			)
		)
		(property "Device Type" "C0201H13"
			(at 2.8321 -3.2639 270)
			(unlocked yes)
			(layer "B.Fab")
			(hide yes)
			(effects
				(font
					(size 1.016 1.016)
					(thickness 0.1524)
				)
				(justify mirror)
			)
		)
		(duplicate_pad_numbers_are_jumpers no)
		(fp_rect
			(start 0.2794 0.6477)
			(end -0.2794 -0.6477)
			(stroke
				(width 0)
				(type default)
			)
			(fill no)
			(layer "B.CrtYd")
		)
		(fp_rect
			(start 0.2794 0.6477)
			(end -0.2794 -0.6477)
			(stroke
				(width 0)
				(type default)
			)
			(fill no)
			(layer "B.Fab")
		)
		(pad "1" smd custom
			(at 0 -0.2794 90)
			(size 0.0762 0.0762)
			(layers "B.Cu" "B.Mask" "B.Paste")
			(net "DUT_AVD_PCIE")
			(options
				(clearance outline)
				(anchor circle)
			)
			(primitives
				(gr_poly
					(pts
						(arc
							(start 0.1524 0.127)
							(mid 0.137521 0.162921)
							(end 0.1016 0.1778)
						)
						(arc
							(start -0.1016 0.1778)
							(mid -0.137521 0.162921)
							(end -0.1524 0.127)
						)
						(arc
							(start -0.1524 -0.127)
							(mid -0.137521 -0.162921)
							(end -0.1016 -0.1778)
						)
						(arc
							(start 0.1016 -0.1778)
							(mid 0.137521 -0.162921)
							(end 0.1524 -0.127)
						)
					)
					(width 0)
					(fill yes)
				)
			)
		)
		(pad "2" smd custom
			(at 0 0.2794 90)
			(size 0.0762 0.0762)
			(layers "B.Cu" "B.Mask" "B.Paste")
			(net "GND")
			(options
				(clearance outline)
				(anchor circle)
			)
			(primitives
				(gr_poly
					(pts
						(arc
							(start 0.1524 0.127)
							(mid 0.137521 0.162921)
							(end 0.1016 0.1778)
						)
						(arc
							(start -0.1016 0.1778)
							(mid -0.137521 0.162921)
							(end -0.1524 0.127)
						)
						(arc
							(start -0.1524 -0.127)
							(mid -0.137521 -0.162921)
							(end -0.1016 -0.1778)
						)
						(arc
							(start 0.1016 -0.1778)
							(mid 0.137521 -0.162921)
							(end 0.1524 -0.127)
						)
					)
					(width 0)
					(fill yes)
				)
			)
		)
	)
	(footprint ""
		(layer "B.Cu")
		(at 252.603 -58.996072 -90)
		(property "Reference" "C548"
			(at 0 0 90)
			(layer "B.SilkS")
			(hide yes)
			(effects
				(font
					(size 1.27 1.27)
				)
				(justify mirror)
			)
		)
		(property "Value" "SCD1U16V1KX-1-GP"
			(at 2.8321 -1.7399 270)
			(unlocked yes)
			(layer "B.Fab")
			(hide yes)
			(effects
				(font
					(size 1.016 1.016)
					(thickness 0.1524)
				)
				(justify mirror)
			)
		)
		(property "Device Type" "C0201H13"
			(at 2.8321 -3.2639 270)
			(unlocked yes)
			(layer "B.Fab")
			(hide yes)
			(effects
				(font
					(size 1.016 1.016)
					(thickness 0.1524)
				)
				(justify mirror)
			)
		)
		(duplicate_pad_numbers_are_jumpers no)
		(fp_rect
			(start 0.2794 0.6477)
			(end -0.2794 -0.6477)
			(stroke
				(width 0)
				(type default)
			)
			(fill no)
			(layer "B.CrtYd")
		)
		(fp_rect
			(start 0.2794 0.6477)
			(end -0.2794 -0.6477)
			(stroke
				(width 0)
				(type default)
			)
			(fill no)
			(layer "B.Fab")
		)
		(pad "1" smd custom
			(at 0 -0.2794 90)
			(size 0.0762 0.0762)
			(layers "B.Cu" "B.Mask" "B.Paste")
			(net "DUT_AVD_PCIE")
			(options
				(clearance outline)
				(anchor circle)
			)
			(primitives
				(gr_poly
					(pts
						(arc
							(start 0.1524 0.127)
							(mid 0.137521 0.162921)
							(end 0.1016 0.1778)
						)
						(arc
							(start -0.1016 0.1778)
							(mid -0.137521 0.162921)
							(end -0.1524 0.127)
						)
						(arc
							(start -0.1524 -0.127)
							(mid -0.137521 -0.162921)
							(end -0.1016 -0.1778)
						)
						(arc
							(start 0.1016 -0.1778)
							(mid 0.137521 -0.162921)
							(end 0.1524 -0.127)
						)
					)
					(width 0)
					(fill yes)
				)
			)
		)
		(pad "2" smd custom
			(at 0 0.2794 90)
			(size 0.0762 0.0762)
			(layers "B.Cu" "B.Mask" "B.Paste")
			(net "GND")
			(options
				(clearance outline)
				(anchor circle)
			)
			(primitives
				(gr_poly
					(pts
						(arc
							(start 0.1524 0.127)
							(mid 0.137521 0.162921)
							(end 0.1016 0.1778)
						)
						(arc
							(start -0.1016 0.1778)
							(mid -0.137521 0.162921)
							(end -0.1524 0.127)
						)
						(arc
							(start -0.1524 -0.127)
							(mid -0.137521 -0.162921)
							(end -0.1016 -0.1778)
						)
						(arc
							(start 0.1016 -0.1778)
							(mid 0.137521 -0.162921)
							(end 0.1524 -0.127)
						)
					)
					(width 0)
					(fill yes)
				)
			)
		)
	)
	(footprint ""
		(layer "B.Cu")
		(at 45.212 -137.668)
		(property "Reference" "TP319"
			(at 0 0 0)
			(layer "B.SilkS")
			(hide yes)
			(effects
				(font
					(size 1.27 1.27)
				)
				(justify mirror)
			)
		)
		(property "Value" "TPAD28-2-GP"
			(at 0.0127 -1.6637 0)
			(unlocked yes)
			(layer "B.Fab")
			(hide yes)
			(effects
				(font
					(size 1.016 1.016)
					(thickness 0.1524)
				)
				(justify mirror)
			)
		)
		(property "Device Type" "TPAD28"
			(at 0.0127 -3.1877 0)
			(unlocked yes)
			(layer "B.Fab")
			(hide yes)
			(effects
				(font
					(size 1.016 1.016)
					(thickness 0.1524)
				)
				(justify mirror)
			)
		)
		(duplicate_pad_numbers_are_jumpers no)
		(fp_poly
			(pts
				(arc
					(start 0.3556 0)
					(mid -0.3556 0)
					(end 0.3556 0)
				)
			)
			(stroke
				(width 0)
				(type default)
			)
			(fill no)
			(layer "B.CrtYd")
		)
		(fp_poly
			(pts
				(arc
					(start 0.6096 0)
					(mid -0.6096 0)
					(end 0.6096 0)
				)
			)
			(stroke
				(width 0)
				(type default)
			)
			(fill no)
			(layer "B.Fab")
		)
		(pad "1" smd circle
			(at 0 0 180)
			(size 0.7112 0.7112)
			(layers "B.Cu" "B.Mask" "B.Paste")
			(net "TP_GPIOO1")
		)
	)
	(footprint ""
		(layer "B.Cu")
		(at 245.684802 -26.67)
		(property "Reference" "TP285"
			(at 0 0 0)
			(layer "B.SilkS")
			(hide yes)
			(effects
				(font
					(size 1.27 1.27)
				)
				(justify mirror)
			)
		)
		(property "Value" "TPAD28-2-GP"
			(at 0.0127 -1.6637 0)
			(unlocked yes)
			(layer "B.Fab")
			(hide yes)
			(effects
				(font
					(size 1.016 1.016)
					(thickness 0.1524)
				)
				(justify mirror)
			)
		)
		(property "Device Type" "TPAD28"
			(at 0.0127 -3.1877 0)
			(unlocked yes)
			(layer "B.Fab")
			(hide yes)
			(effects
				(font
					(size 1.016 1.016)
					(thickness 0.1524)
				)
				(justify mirror)
			)
		)
		(duplicate_pad_numbers_are_jumpers no)
		(fp_poly
			(pts
				(arc
					(start 0.3556 0)
					(mid -0.3556 0)
					(end 0.3556 0)
				)
			)
			(stroke
				(width 0)
				(type default)
			)
			(fill no)
			(layer "B.CrtYd")
		)
		(fp_poly
			(pts
				(arc
					(start 0.6096 0)
					(mid -0.6096 0)
					(end 0.6096 0)
				)
			)
			(stroke
				(width 0)
				(type default)
			)
			(fill no)
			(layer "B.Fab")
		)
		(pad "1" smd circle
			(at 0 0 180)
			(size 0.7112 0.7112)
			(layers "B.Cu" "B.Mask" "B.Paste")
			(net "TWI_SDA4")
		)
	)
	(footprint ""
		(layer "B.Cu")
		(at 186.0804 -61.595)
		(property "Reference" "C583"
			(at 0 0 0)
			(layer "B.SilkS")
			(hide yes)
			(effects
				(font
					(size 1.27 1.27)
				)
				(justify mirror)
			)
		)
		(property "Value" "SC4D7U16V5KX-1-GP"
			(at 0.0762 -6.1214 0)
			(unlocked yes)
			(layer "B.Fab")
			(hide yes)
			(effects
				(font
					(size 1.016 1.016)
					(thickness 0.1524)
				)
				(justify mirror)
			)
		)
		(property "Device Type" "C805H56"
			(at 0.0762 -8.1534 0)
			(unlocked yes)
			(layer "B.Fab")
			(hide yes)
			(effects
				(font
					(size 1.016 1.016)
					(thickness 0.1524)
				)
				(justify mirror)
			)
		)
		(duplicate_pad_numbers_are_jumpers no)
		(fp_line
			(start -0.635 0)
			(end 0.635 0)
			(stroke
				(width 0.508)
				(type default)
			)
			(layer "B.SilkS")
		)
		(fp_rect
			(start 0.9652 1.778)
			(end -0.9652 -1.778)
			(stroke
				(width 0)
				(type default)
			)
			(fill no)
			(layer "B.CrtYd")
		)
		(fp_poly
			(pts
				(xy 0.9652 -1.778) (xy -0.9652 -1.778) (xy -0.9652 1.778) (xy 0.9652 1.778)
			)
			(stroke
				(width 0)
				(type default)
			)
			(fill no)
			(layer "B.Fab")
		)
		(pad "1" smd rect
			(at 0 -0.9652 180)
			(size 1.397 1.143)
			(layers "B.Cu" "B.Mask" "B.Paste")
			(net "DUT_AVD_PCIE")
		)
		(pad "2" smd rect
			(at 0 0.9652 180)
			(size 1.397 1.143)
			(layers "B.Cu" "B.Mask" "B.Paste")
			(net "GND")
		)
	)
	(footprint ""
		(layer "B.Cu")
		(at 337.9216 -175.7426)
		(property "Reference" "R3230"
			(at 0 0 0)
			(layer "B.SilkS")
			(hide yes)
			(effects
				(font
					(size 1.27 1.27)
				)
				(justify mirror)
			)
		)
		(property "Value" "0R2J-2-GP"
			(at -0.064008 -3.993896 0)
			(unlocked yes)
			(layer "B.Fab")
			(hide yes)
			(effects
				(font
					(size 1.016 1.016)
					(thickness 0.1524)
				)
				(justify mirror)
			)
		)
		(property "Device Type" "R402H16"
			(at -0.064008 -5.517896 0)
			(unlocked yes)
			(layer "B.Fab")
			(hide yes)
			(effects
				(font
					(size 1.016 1.016)
					(thickness 0.1524)
				)
				(justify mirror)
			)
		)
		(duplicate_pad_numbers_are_jumpers no)
		(fp_line
			(start -0.508 -0.9398)
			(end 0.508 -0.9398)
			(stroke
				(width 0.1524)
				(type default)
			)
			(layer "B.SilkS")
		)
		(fp_line
			(start 0.508 -0.9398)
			(end 0.508 0.9398)
			(stroke
				(width 0.1524)
				(type default)
			)
			(layer "B.SilkS")
		)
		(fp_rect
			(start 0.508 0.9398)
			(end -0.508 -0.9398)
			(stroke
				(width 0)
				(type default)
			)
			(fill no)
			(layer "B.CrtYd")
		)
		(fp_rect
			(start 0.508 0.9398)
			(end -0.508 -0.9398)
			(stroke
				(width 0)
				(type default)
			)
			(fill no)
			(layer "B.Fab")
		)
		(pad "1" smd custom
			(at 0 -0.4445 180)
			(size 0.1397 0.1397)
			(layers "B.Cu" "B.Mask" "B.Paste")
			(net "SSD_PERST_Y9")
			(options
				(clearance outline)
				(anchor circle)
			)
			(primitives
				(gr_poly
					(pts
						(arc
							(start -0.1778 0.2794)
							(mid -0.249642 0.249642)
							(end -0.2794 0.1778)
						)
						(arc
							(start -0.2794 -0.1778)
							(mid -0.249642 -0.249642)
							(end -0.1778 -0.2794)
						)
						(arc
							(start 0.1778 -0.2794)
							(mid 0.249642 -0.249642)
							(end 0.2794 -0.1778)
						)
						(arc
							(start 0.2794 0.1778)
							(mid 0.249642 0.249642)
							(end 0.1778 0.2794)
						)
					)
					(width 0)
					(fill yes)
				)
			)
		)
		(pad "2" smd custom
			(at 0 0.4445 180)
			(size 0.1397 0.1397)
			(layers "B.Cu" "B.Mask" "B.Paste")
			(net "SSD_PERST#9_R")
			(options
				(clearance outline)
				(anchor circle)
			)
			(primitives
				(gr_poly
					(pts
						(arc
							(start -0.1778 0.2794)
							(mid -0.249642 0.249642)
							(end -0.2794 0.1778)
						)
						(arc
							(start -0.2794 -0.1778)
							(mid -0.249642 -0.249642)
							(end -0.1778 -0.2794)
						)
						(arc
							(start 0.1778 -0.2794)
							(mid 0.249642 -0.249642)
							(end 0.2794 -0.1778)
						)
						(arc
							(start 0.2794 0.1778)
							(mid 0.249642 0.249642)
							(end 0.1778 0.2794)
						)
					)
					(width 0)
					(fill yes)
				)
			)
		)
	)
)
